# BASEBOARD_FAB2 (Tioga Pass) — schematic netlist excerpt (pin names and nets, part order shuffled) for the footprints in the layout excerpt that follows; sources: Cadence DE-HDL packaged netlist, KiCad conversion of Wiwynn_Tioga_Pass_MB.brd

L1D3  IND-120NH-30-GP  pkg DISCRET-GB2  page 207 : S = VR_PVCCIN_CPU1_PHASE2 ; F = PVCCIN_CPU1
C8E1  CAP_A  0.1UF 16V 10% X7R  pkg 0402V  page 181 : A = P3V3_STBY ; B = GND
R9E3  RES  10.0K 1% CHIP  pkg 0402  page 139 : A = P3V3_STBY ; B = PU_JTAG_SPRV_TMS

(kicad_pcb
	(version 20260206)
	(generator "pcbnew")
	(generator_version "10.0")
	(general
		(thickness 1.6)
		(legacy_teardrops no)
	)
	(paper "A4")
	(title_block
		(title "Wiwynn_Tioga_Pass_MB.brd")
		(comment 1 "Tioga Pass / footprints 1233-1235 of 4770")
	)
	(layers
		(0 "F.Cu" signal "TOP")
		(4 "In1.Cu" signal "L2GND")
		(6 "In2.Cu" signal "L3")
		(8 "In3.Cu" signal "L4GND")
		(10 "In4.Cu" signal "L5")
		(12 "In5.Cu" signal "L6GND")
		(14 "In6.Cu" signal "L7VCC")
		(16 "In7.Cu" signal "L8VCC")
		(18 "In8.Cu" signal "L9GND")
		(20 "In9.Cu" signal "L10")
		(22 "In10.Cu" signal "L11GND")
		(24 "In11.Cu" signal "L12")
		(26 "In12.Cu" signal "L13GND")
		(2 "B.Cu" signal "BOTTOM")
		(9 "F.Adhes" user "F.Adhesive")
		(11 "B.Adhes" user "B.Adhesive")
		(13 "F.Paste" user "Package Geometry/Pastemask Top")
		(15 "B.Paste" user "Package Geometry/Pastemask Bottom")
		(5 "F.SilkS" user "Ref Des/Silkscreen Top")
		(7 "B.SilkS" user "Ref Des/Silkscreen Bottom")
		(1 "F.Mask" user "Board Geometry/Soldermask Top")
		(3 "B.Mask" user "Board Geometry/Soldermask Bottom")
		(17 "Dwgs.User" user "User.Drawings")
		(19 "Cmts.User" user "User.Comments")
		(21 "Eco1.User" user "User.Eco1")
		(23 "Eco2.User" user "User.Eco2")
		(25 "Edge.Cuts" user "Board Geometry/Outline")
		(27 "Margin" user)
		(31 "F.CrtYd" user "Package Geometry/Place Bound Top")
		(29 "B.CrtYd" user "Package Geometry/Place Bound Bottom")
		(35 "F.Fab" user "Ref Des/Assembly Top")
		(33 "B.Fab" user "Ref Des/Assembly Bottom")
	)
	(footprint ""
		(layer "F.Cu")
		(at 488.3912 -50.6857)
		(property "Reference" "R9E3"
			(at 0 0 0)
			(layer "F.SilkS")
			(hide yes)
			(effects
				(font
					(size 1.27 1.27)
				)
			)
		)
		(property "Value" ""
			(at 0 0 0)
			(layer "F.Fab")
			(effects
				(font
					(size 1.27 1.27)
				)
			)
		)
		(duplicate_pad_numbers_are_jumpers no)
		(fp_poly
			(pts
				(xy -0.2794 -0.1016) (xy 0.2794 -0.1016) (xy 0.2794 0.9906) (xy -0.2794 0.9906)
			)
			(stroke
				(width 0)
				(type default)
			)
			(fill no)
			(layer "F.CrtYd")
		)
		(fp_line
			(start -0.2794 -0.1016)
			(end -0.2794 0.9906)
			(stroke
				(width 0.1)
				(type default)
			)
			(layer "F.Fab")
		)
		(fp_line
			(start -0.2794 0.9906)
			(end 0.2794 0.9906)
			(stroke
				(width 0.1)
				(type default)
			)
			(layer "F.Fab")
		)
		(fp_line
			(start 0.2794 -0.1016)
			(end -0.2794 -0.1016)
			(stroke
				(width 0.1)
				(type default)
			)
			(layer "F.Fab")
		)
		(fp_line
			(start 0.2794 0.9906)
			(end 0.2794 -0.1016)
			(stroke
				(width 0.1)
				(type default)
			)
			(layer "F.Fab")
		)
		(pad "1" smd rect
			(at 0 0)
			(size 0.508 0.508)
			(layers "F.Cu" "F.Mask" "F.Paste")
			(net "P3V3_STBY")
		)
		(pad "2" smd rect
			(at 0 0.889)
			(size 0.508 0.508)
			(layers "F.Cu" "F.Mask" "F.Paste")
			(net "PU_JTAG_SPRV_TMS")
		)
		(zone
			(layer "F.Cu")
			(hatch none 0.5)
			(connect_pads
				(clearance 0)
			)
			(min_thickness 0.25)
			(keepout
				(tracks allowed)
				(vias not_allowed)
				(pads allowed)
				(copperpour not_allowed)
				(footprints allowed)
			)
			(placement
				(enabled no)
				(sheetname "")
			)
			(fill
				(thermal_gap 0.5)
				(thermal_bridge_width 0.5)
				(island_removal_mode 0)
			)
			(polygon
				(pts
					(xy 488.1372 -50.4317) (xy 488.6452 -50.4317) (xy 488.6452 -50.0507) (xy 488.1372 -50.0507)
				)
			)
		)
		(zone
			(layer "F.Cu")
			(hatch none 0.5)
			(connect_pads
				(clearance 0)
			)
			(min_thickness 0.25)
			(keepout
				(tracks not_allowed)
				(vias allowed)
				(pads allowed)
				(copperpour not_allowed)
				(footprints allowed)
			)
			(placement
				(enabled no)
				(sheetname "")
			)
			(fill
				(thermal_gap 0.5)
				(thermal_bridge_width 0.5)
				(island_removal_mode 0)
			)
			(polygon
				(pts
					(xy 488.1372 -50.0507) (xy 488.6452 -50.0507) (xy 488.6452 -50.4317) (xy 488.1372 -50.4317)
				)
			)
		)
	)
	(footprint ""
		(layer "F.Cu")
		(at 417.83 -86.4235)
		(property "Reference" "C8E1"
			(at 0 0 0)
			(layer "F.SilkS")
			(hide yes)
			(effects
				(font
					(size 1.27 1.27)
				)
			)
		)
		(property "Value" ""
			(at 0 0 0)
			(layer "F.Fab")
			(effects
				(font
					(size 1.27 1.27)
				)
			)
		)
		(duplicate_pad_numbers_are_jumpers no)
		(fp_poly
			(pts
				(xy 0.3048 -0.1016) (xy 0.3048 0.9906) (xy -0.3048 0.9906) (xy -0.3048 -0.1016)
			)
			(stroke
				(width 0)
				(type default)
			)
			(fill no)
			(layer "F.CrtYd")
		)
		(fp_line
			(start -0.3048 -0.1016)
			(end -0.3048 0.9906)
			(stroke
				(width 0.1)
				(type default)
			)
			(layer "F.Fab")
		)
		(fp_line
			(start -0.3048 0.9906)
			(end 0.3048 0.9906)
			(stroke
				(width 0.1)
				(type default)
			)
			(layer "F.Fab")
		)
		(fp_line
			(start 0.3048 -0.1016)
			(end -0.3048 -0.1016)
			(stroke
				(width 0.1)
				(type default)
			)
			(layer "F.Fab")
		)
		(fp_line
			(start 0.3048 0.9906)
			(end 0.3048 -0.1016)
			(stroke
				(width 0.1)
				(type default)
			)
			(layer "F.Fab")
		)
		(pad "1" smd rect
			(at 0 0)
			(size 0.508 0.508)
			(layers "F.Cu" "F.Mask" "F.Paste")
			(net "P3V3_STBY")
		)
		(pad "2" smd rect
			(at 0 0.889)
			(size 0.508 0.508)
			(layers "F.Cu" "F.Mask" "F.Paste")
			(net "GND")
		)
		(zone
			(layer "F.Cu")
			(hatch none 0.5)
			(connect_pads
				(clearance 0)
			)
			(min_thickness 0.25)
			(keepout
				(tracks allowed)
				(vias not_allowed)
				(pads allowed)
				(copperpour not_allowed)
				(footprints allowed)
			)
			(placement
				(enabled no)
				(sheetname "")
			)
			(fill
				(thermal_gap 0.5)
				(thermal_bridge_width 0.5)
				(island_removal_mode 0)
			)
			(polygon
				(pts
					(xy 417.576 -86.1695) (xy 418.084 -86.1695) (xy 418.084 -85.7885) (xy 417.576 -85.7885)
				)
			)
		)
		(zone
			(layer "F.Cu")
			(hatch none 0.5)
			(connect_pads
				(clearance 0)
			)
			(min_thickness 0.25)
			(keepout
				(tracks not_allowed)
				(vias allowed)
				(pads allowed)
				(copperpour not_allowed)
				(footprints allowed)
			)
			(placement
				(enabled no)
				(sheetname "")
			)
			(fill
				(thermal_gap 0.5)
				(thermal_bridge_width 0.5)
				(island_removal_mode 0)
			)
			(polygon
				(pts
					(xy 417.576 -85.7885) (xy 418.084 -85.7885) (xy 418.084 -86.1695) (xy 417.576 -86.1695)
				)
			)
		)
	)
	(footprint ""
		(layer "F.Cu")
		(at 40.036496 -65.159382)
		(property "Reference" "L1D3"
			(at 3.378708 -4.251706 0)
			(unlocked yes)
			(layer "F.SilkS")
			(effects
				(font
					(size 0.4064 0.254)
					(thickness 0.1524)
				)
			)
		)
		(property "Value" ""
			(at 0 0 0)
			(layer "F.Fab")
			(effects
				(font
					(size 1.27 1.27)
				)
			)
		)
		(duplicate_pad_numbers_are_jumpers no)
		(fp_line
			(start -1.1303 -3.199892)
			(end 8.3693 -3.199892)
			(stroke
				(width 0.1524)
				(type default)
			)
			(layer "F.SilkS")
		)
		(fp_line
			(start -1.1303 -1.6637)
			(end -1.1303 -3.199892)
			(stroke
				(width 0.1524)
				(type default)
			)
			(layer "F.SilkS")
		)
		(fp_line
			(start -1.1303 3.199892)
			(end -1.1303 1.6637)
			(stroke
				(width 0.1524)
				(type default)
			)
			(layer "F.SilkS")
		)
		(fp_line
			(start 8.3693 -3.199892)
			(end 8.3693 -1.6637)
			(stroke
				(width 0.1524)
				(type default)
			)
			(layer "F.SilkS")
		)
		(fp_line
			(start 8.3693 1.6637)
			(end 8.3693 3.199892)
			(stroke
				(width 0.1524)
				(type default)
			)
			(layer "F.SilkS")
		)
		(fp_line
			(start 8.3693 3.199892)
			(end -1.1303 3.199892)
			(stroke
				(width 0.1524)
				(type default)
			)
			(layer "F.SilkS")
		)
		(fp_rect
			(start -1.1303 3.199892)
			(end 8.3693 -3.199892)
			(stroke
				(width 0)
				(type default)
			)
			(fill no)
			(layer "F.CrtYd")
		)
		(fp_line
			(start -1.1303 -3.199892)
			(end 8.3693 -3.199892)
			(stroke
				(width 0.1)
				(type default)
			)
			(layer "F.Fab")
		)
		(fp_line
			(start -1.1303 3.199892)
			(end -1.1303 -3.199892)
			(stroke
				(width 0.1)
				(type default)
			)
			(layer "F.Fab")
		)
		(fp_line
			(start 8.3693 -3.199892)
			(end 8.3693 3.199892)
			(stroke
				(width 0.1)
				(type default)
			)
			(layer "F.Fab")
		)
		(fp_line
			(start 8.3693 3.199892)
			(end -1.1303 3.199892)
			(stroke
				(width 0.1)
				(type default)
			)
			(layer "F.Fab")
		)
		(pad "1" smd rect
			(at 0 0)
			(size 3.683 2.667)
			(layers "F.Cu" "F.Mask" "F.Paste")
			(net "VR_PVCCIN_CPU1_PHASE2")
		)
		(pad "2" smd rect
			(at 7.239 0)
			(size 3.683 2.667)
			(layers "F.Cu" "F.Mask" "F.Paste")
			(net "PVCCIN_CPU1")
		)
	)
)
